FILE_TYPE = CONNECTIVITY;
{Allegro Design Entry HDL 16.6-p007 (v16-6-112F) 10/10/2012}
"PAGE_NUMBER" = 175;
0"NC";
1"GND\g";
2"GND\g";
3"P3V3_STBY\g";
4"GND\g";
5"GND\g";
6"GND\g";
7"GND\g";
8"P3V3_STBY\g";
9"P3V3_STBY\g";
10"GND\g";
11"P5V_STBY\g";
12"P3V3_STBY\g";
13"GND\g";
14"P3V3_STBY\g";
15"GND\g";
16"P3V3_STBY\g";
17"P5V_STBY\g";
18"GND\g";
19"GND\g";
20"FP_PWR_BTN_R_N";
21"FP_ID_LED_P5V_STBY_N";
22"FM_DEBUG_RST_BTN_N";
23"FM_SPEAKER_PCH_N";
24"FM_BEEP_LED_P";
25"FP_RST_BTN_R_N";
26"RST_SYSTEM_BTN_N";
27"FP_PWR_BTN_R1_N";
28"FM_PWR_BTN_N";
29"PWRGD_P3V3";
30"FM_BIOS_TOP_SWAP_SPKR";
31"FP_PWR_ID_LED_N";
32"PWRGD_P3V3_R";
33"RST_SYSTEM_BTN_BUF_N";
34"FP_PWR_BTN_BUF1_N";
35"FM_PWR_BTN_R_N";
36"FP_RST_BTN_BUF1_N";
37"FP_ID_LED_XOR_R";
%"CAP_A"
"1","(-4975,3950)","0","dev_discrete","I11";
;
PART_NUMBER"D97712-004"
VOLTAGE"6.3V"
VALUE"1.0UF"
PACK_TYPE"0402V"
MATERIAL"X6S"
LOCATION"C1L18"
TOLERANCE"10%"
BOM_COST"MIO_CHASSIS"
CDS_SEC"1"
SEC_TYPE"0402V"
SEC"1"
ROOM"MIO_CHASSIS"
CDS_LOCATION"C1L18"
CDS_LIB"dev_discrete";
"B"
$PN"2"1;
"A"
$PN"1"27;
%"GND"
"1","(-4975,3675)","0","mstr_symbols","I12";
;
VOLTAGE"0.0V"
CDS_LIB"mstr_symbols"
SIZE"1B"
BODY_TYPE"PLUMBING"
HDL_POWER"GND";
"A\NAC"1;
%"RES"
"1","(-2275,4075)","0","mstr_discrete","I13";
;
CDS_SEC"1"
PACK_TYPE"0402"
MATERIAL"CHIP"
WATTAGE"1/16W"
VALUE"33.2"
TOLERANCE"1%"
LOCATION"R1L26"
PART_NUMBER"G21796-074"
SEC_TYPE"0402"
BOM_COST"MIO_CHASSIS"
ROOM"MIO_CHASSIS"
SEC"1"
CDS_LOCATION"R1L26"
CDS_LIB"mstr_discrete";
"B"
$PN"2"28;
"A"
$PN"1"35;
%"CAP_A"
"1","(-4925,2550)","0","dev_discrete","I19";
;
VALUE"1.0UF"
LOCATION"C1L10"
VOLTAGE"6.3V"
PACK_TYPE"0402V"
PART_NUMBER"D97712-004"
MATERIAL"X6S"
TOLERANCE"10%"
SEC"1"
ROOM"MIO_CHASSIS"
BOM_COST"MIO_CHASSIS"
CDS_SEC"1"
SEC_TYPE"0402V"
CDS_LOCATION"C1L10"
CDS_LIB"dev_discrete";
"B"
$PN"2"2;
"A"
$PN"1"25;
%"GND"
"1","(-4925,2275)","0","mstr_symbols","I20";
;
CDS_LIB"mstr_symbols"
VOLTAGE"0.0V"
SIZE"1B"
BODY_TYPE"PLUMBING"
HDL_POWER"GND";
"A\NAC"2;
%"P3V3_STBY"
"1","(-5875,3400)","0","mstr_symbols","I21";
;
CDS_LIB"mstr_symbols"
SIZE"1B"
VOLTAGE"3.3V"
BODY_TYPE"PLUMBING"
HDL_POWER"P3V3_STBY";
"G\NAC"3;
%"RES"
"1","(-5600,2775)","0","mstr_discrete","I22";
;
CDS_SEC"1"
TOLERANCE"1%"
LOCATION"R1L22"
VALUE"200.0"
WATTAGE"1/16W"
MATERIAL"CHIP"
PACK_TYPE"0402"
PART_NUMBER"G21796-004"
CDS_LIB"mstr_discrete"
BOM_COST"MIO_CHASSIS"
SEC_TYPE"0402"
SEC"1"
CDS_LOCATION"R1L22"
ROOM"MIO_CHASSIS";
"B"
$PN"2"25;
"A"
$PN"1"22;
%"GND"
"1","(-7625,2250)","0","mstr_symbols","I27";
;
CDS_LIB"mstr_symbols"
SIZE"1B"
VOLTAGE"0.0V"
BODY_TYPE"PLUMBING"
HDL_POWER"GND";
"A\NAC"4;
%"GND"
"1","(-7675,3650)","0","mstr_symbols","I3";
;
CDS_LIB"mstr_symbols"
SIZE"1B"
VOLTAGE"0.0V"
BODY_TYPE"PLUMBING"
HDL_POWER"GND";
"A\NAC"5;
%"CAP_A"
"1","(-2950,4450)","0","dev_discrete","I37";
;
PART_NUMBER"A36096-030"
VALUE"0.1UF"
VOLTAGE"16V"
PACK_TYPE"0402V"
LOCATION"C1L17"
MATERIAL"X7R"
TOLERANCE"10%"
ROOM"MIO_CHASSIS"
CDS_LOCATION"C1L17"
BOM_COST"MIO_CHASSIS"
CDS_SEC"1"
SEC_TYPE"0402V"
SEC"1"
CDS_LIB"dev_discrete";
"B"
$PN"2"7;
"A"
$PN"1"8;
%"CAP_A"
"1","(-2975,3000)","0","dev_discrete","I38";
;
VOLTAGE"16V"
MATERIAL"X7R"
PART_NUMBER"A36096-030"
PACK_TYPE"0402V"
TOLERANCE"10%"
LOCATION"C1L9"
VALUE"0.1UF"
BOM_COST"MIO_CHASSIS"
SEC_TYPE"0402V"
ROOM"MIO_CHASSIS"
CDS_LOCATION"C1L9"
CDS_LIB"dev_discrete"
CDS_SEC"1"
SEC"1";
"B"
$PN"2"6;
"A"
$PN"1"9;
%"RES"
"1","(-5650,4175)","0","mstr_discrete","I4";
;
CDS_SEC"1"
PACK_TYPE"0402"
MATERIAL"CHIP"
LOCATION"R1L31"
PART_NUMBER"G21796-004"
VALUE"200.0"
WATTAGE"1/16W"
TOLERANCE"1%"
SEC"1"
BOM_COST"MIO_CHASSIS"
SEC_TYPE"0402"
ROOM"MIO_CHASSIS"
CDS_LOCATION"R1L31"
CDS_LIB"mstr_discrete";
"B"
$PN"2"27;
"A"
$PN"1"20;
%"CAP_A"
"1","(-575,3500)","0","dev_discrete","I40";
;
VOLTAGE"16V"
VALUE"0.1UF"
LOCATION"C9A3"
TOLERANCE"10%"
MATERIAL"X7R"
PART_NUMBER"A36096-030"
PACK_TYPE"0402V"
SEC"1"
SEC_TYPE"0402V"
BOM_COST"MIO_CHASSIS"
ROOM"MIO_CHASSIS"
CDS_LOCATION"C9A3"
CDS_SEC"1"
CDS_LIB"dev_discrete";
"B"
$PN"2"15;
"A"
$PN"1"14;
%"GND"
"1","(-2975,2800)","0","mstr_symbols","I41";
;
CDS_LIB"mstr_symbols"
VOLTAGE"0.0V"
SIZE"1B"
BODY_TYPE"PLUMBING"
HDL_POWER"GND";
"A\NAC"6;
%"GND"
"1","(-2950,4200)","0","mstr_symbols","I42";
;
SIZE"1B"
VOLTAGE"0.0V"
CDS_LIB"mstr_symbols"
BODY_TYPE"PLUMBING"
HDL_POWER"GND";
"A\NAC"7;
%"P3V3_STBY"
"1","(-2950,4700)","0","mstr_symbols","I43";
;
VOLTAGE"3.3V"
CDS_LIB"mstr_symbols"
SIZE"1B"
BODY_TYPE"PLUMBING"
HDL_POWER"P3V3_STBY";
"G\NAC"8;
%"P3V3_STBY"
"1","(-2975,3250)","0","mstr_symbols","I44";
;
CDS_LIB"mstr_symbols"
VOLTAGE"3.3V"
SIZE"1B"
BODY_TYPE"PLUMBING"
HDL_POWER"P3V3_STBY";
"G\NAC"9;
%"RES"
"1","(-4000,1550)","0","mstr_discrete","I45";
;
CDS_SEC"1"
VALUE"221"
LOCATION"R1L33"
PART_NUMBER"G21796-271"
MATERIAL"CHIP"
PACK_TYPE"0402"
TOLERANCE"1.0%"
WATTAGE"1/16W"
SEC_TYPE"0402"
BOM_COST"MIO_CHASSIS"
CDS_LIB"mstr_discrete"
ROOM"MIO_CHASSIS"
SEC"1"
CDS_LOCATION"R1L33";
"B"
$PN"2"16;
"A"
$PN"1"24;
%"FET_N"
"8","(-5025,1175)","0","mstr_discrete","I49";
;
CDS_SEC"1"
PART_NUMBER"C79254-001"
LOCATION"Q9A3"
VALUE"2N7002"
MATERIAL"FET"
PACK_TYPE"SOT23LF"
SEC_TYPE"SOT23LF"
BOM_COST"MIO_CHASSIS"
SEC"1"
CDS_LOCATION"Q9A3"
ROOM"MIO_CHASSIS"
CDS_LIB"mstr_discrete";
"GATE"
$PN"1"30;
"DRN"
$PN"3"23;
"SRC"
$PN"2"10;
%"RES"
"2","(-5925,4475)","0","mstr_discrete","I5";
;
CDS_SEC"1"
PART_NUMBER"G21796-072"
PACK_TYPE"0402"
WATTAGE"1/16W"
MATERIAL"CHIP"
TOLERANCE"1%"
VALUE"4.75K"
LOCATION"R1L27"
ROOM"MIO_CHASSIS"
SEC"1"
SEC_TYPE"0402"
BOM_COST"MIO_CHASSIS"
CDS_LOCATION"R1L27"
CDS_LIB"mstr_discrete";
"A"
$PN"1"12;
"B"
$PN"2"20;
%"LED"
"3","(-1700,1025)","0","mstr_discrete","I50";
;
LOCATION"DS9A1"
MATERIAL"IC"
COLOR"BLUE"
PART_NUMBER"C96565-012"
CDS_LIB"mstr_discrete"
PACK_TYPE"1NC"
BOM_COST"MIO_CHASSIS"
CDS_SEC"1"
$SEC"1"
CDS_LOCATION"DS9A1"
ROOM"MIO_CHASSIS";
"A"
$PN"2"37;
"C"
$PN"1"21;
%"GND"
"1","(-5025,750)","0","mstr_symbols","I54";
;
CDS_LIB"mstr_symbols"
SIZE"1B"
VOLTAGE"0.0V"
BODY_TYPE"PLUMBING"
HDL_POWER"GND";
"A\NAC"10;
%"TTL1G86"
"1","(-2750,1025)","0","mstr_ttl","I57";
;
VALUE"74AHCT1G86"
POWER_GROUP"VCC=P5V_STBY;GND=GND;"
PART_NUMBER"D39848-001"
MATERIAL"IC"
LOCATION"U1L2"
CDS_LIB"mstr_ttl"
ROOM"MIO_CHASSIS"
$SEC"1"
CDS_SEC"1"
BOM_COST"MIO_CHASSIS"
PACK_TYPE"SOTLF"
CDS_LOCATION"U1L2";
"Y"
$PN"4"21;
"A"
$PN"1"32;
"B"
$PN"2"31;
%"RES"
"2","(-1175,1350)","0","mstr_discrete","I58";
;
CDS_SEC"1"
WATTAGE"1/16W"
MATERIAL"CHIP"
PACK_TYPE"0402"
PART_NUMBER"G21497-024"
LOCATION"R1L8"
VALUE"470.0"
TOLERANCE"5%"
CDS_LOCATION"R1L8"
CDS_LIB"mstr_discrete"
ROOM"MIO_CHASSIS"
SEC"1"
BOM_COST"MIO_CHASSIS"
SEC_TYPE"0402";
"A"
$PN"1"11;
"B"
$PN"2"37;
%"P5V_STBY"
"1","(-1175,1700)","0","mstr_symbols","I59";
;
VOLTAGE"5.0V"
CDS_LIB"mstr_symbols"
SIZE"1B"
BODY_TYPE"PLUMBING"
HDL_POWER"P5V_STBY";
"G\NAC"11;
%"P3V3_STBY"
"1","(-5925,4800)","0","mstr_symbols","I6";
;
SIZE"1B"
CDS_LIB"mstr_symbols"
VOLTAGE"3.3V"
BODY_TYPE"PLUMBING"
HDL_POWER"P3V3_STBY";
"G\NAC"12;
%"RES"
"1","(-3525,1075)","0","mstr_discrete","I63";
;
CDS_SEC"1"
WATTAGE"1/16W"
VALUE"0.0"
PART_NUMBER"G21497-005"
LOCATION"R1L12"
TOLERANCE"5%"
PACK_TYPE"0402"
MATERIAL"CHIP"
BOM_COST"MIO_CHASSIS"
ROOM"MIO_CHASSIS"
SEC"1"
SEC_TYPE"0402"
CDS_LIB"mstr_discrete"
CDS_LOCATION"R1L12";
"B"
$PN"2"32;
"A"
$PN"1"29;
%"CAP_A"
"1","(-2900,1725)","0","dev_discrete","I64";
;
TOLERANCE"10%"
MATERIAL"X7R"
PACK_TYPE"0402V"
VOLTAGE"16V"
LOCATION"C1L4"
PART_NUMBER"A36096-030"
VALUE"0.1UF"
SEC_TYPE"0402V"
BOM_COST"MIO_CHASSIS"
CDS_LOCATION"C1L4"
SEC"1"
ROOM"MIO_CHASSIS"
CDS_SEC"1"
CDS_LIB"dev_discrete";
"B"
$PN"2"13;
"A"
$PN"1"17;
%"GND"
"1","(-2900,1475)","0","mstr_symbols","I66";
;
SIZE"1B"
CDS_LIB"mstr_symbols"
VOLTAGE"0.0V"
BODY_TYPE"PLUMBING"
HDL_POWER"GND";
"A\NAC"13;
%"LED"
"3","(-4600,1550)","0","mstr_discrete","I67";
;
CDS_SEC"1"
LOCATION"DS9A3"
MATERIAL"IC"
PART_NUMBER"C96565-003"
COLOR"YELLOW"
CDS_LIB"mstr_discrete"
PACK_TYPE"1NCLF"
SEC_TYPE"1NCLF"
BOM_COST"MIO_CHASSIS"
SEC"1"
CDS_LOCATION"DS9A3"
ROOM"MIO_CHASSIS";
"A"
$PN"2"24;
"C"
$PN"1"23;
%"P3V3_STBY"
"1","(-575,3800)","0","mstr_symbols","I70";
;
CDS_LIB"mstr_symbols"
VOLTAGE"3.3V"
SIZE"1B"
BODY_TYPE"PLUMBING"
HDL_POWER"P3V3_STBY";
"G\NAC"14;
%"GND"
"1","(-575,3200)","0","mstr_symbols","I71";
;
SIZE"1B"
VOLTAGE"0.0V"
CDS_LIB"mstr_symbols"
BODY_TYPE"PLUMBING"
HDL_POWER"GND";
"A\NAC"15;
%"SWITCH_D37771002"
"1","(-7075,2675)","3","mstr_misc","I78";
;
CDS_SEC"1"
LOCATION"S9A1"
MATERIAL"IC"
PART_NUMBER"D37771-002"
CDS_LOCATION"S9A1"
CDS_LIB"mstr_misc"
CDS_LMAN_SYM_OUTLINE"-100,125,100,-75"
SEC"1"
SEC_TYPE"SM"
PACK_TYPE"SM"
ROOM"MIO_CHASSIS"
BOM_COST"MIO_CHASSIS";
"PIN4"
$PN"4"4;
"PIN2"
$PN"2"22;
"PIN1"
$PN"1"22;
"PIN3"
$PN"3"4;
%"P3V3_STBY"
"1","(-3700,1825)","0","mstr_symbols","I85";
;
SIZE"1B"
CDS_LIB"mstr_symbols"
VOLTAGE"3.3V"
BODY_TYPE"PLUMBING"
HDL_POWER"P3V3_STBY";
"G\NAC"16;
%"P5V_STBY"
"1","(-2900,1975)","0","mstr_symbols","I86";
;
SIZE"1B"
CDS_LIB"mstr_symbols"
VOLTAGE"5.0V"
BODY_TYPE"PLUMBING"
HDL_POWER"P5V_STBY";
"G\NAC"17;
%"SWITCH_D37771002"
"1","(-7200,4150)","2","mstr_misc","I92";
;
CDS_SEC"1"
CDS_LOCATION"S9A2"
MATERIAL"IC"
PART_NUMBER"D37771-002"
LOCATION"S9A2"
PACK_TYPE"SM"
SEC"1"
SEC_TYPE"SM"
CDS_LIB"mstr_misc"
CDS_LMAN_SYM_OUTLINE"-100,125,100,-75"
BOM_COST"MIO_CHASSIS"
ROOM"MIO_CHASSIS";
"PIN4"
$PN"4"20;
"PIN2"
$PN"2"5;
"PIN1"
$PN"1"5;
"PIN3"
$PN"3"20;
%"TC7PZ14FU-GP"
"1","(-3725,2725)","0","w_hdl","I93";
;
CDS_SEC"1"
CDS_LOCATION"U9A3"
LOCATION"U9A3"
VALUE"TC7PZ14FU-GP"
CDS_LIB"w_hdl"
CDS_LMAN_SYM_OUTLINE"-200,150,200,-150"
SEC"1"
SEC_TYPE"DISCRET-GA1"
PACK_TYPE"DISCRET-GA1"
PART_NUMBER"073.7PZ14.0007";
"1Y"
$PN"6"36;
"VCC"
$PN"5"9;
"2Y"
$PN"4"33;
"2A"
$PN"3"36;
"GND"
$PN"2"18;
"1A"
$PN"1"25;
%"RES"
"1","(-2225,2675)","0","mstr_discrete","I95";
;
PART_NUMBER"G21796-017"
LOCATION"R9A9"
TOLERANCE"1%"
VALUE"100.0"
WATTAGE"1/16W"
MATERIAL"CHIP"
PACK_TYPE"0402"
CDS_LIB"mstr_discrete"
SEC_TYPE"0402"
BOM_COST"MIO_CHASSIS"
SEC"1"
CDS_LOCATION"R9A9"
ROOM"MIO_CHASSIS"
CDS_SEC"1";
"B"
$PN"2"26;
"A"
$PN"1"33;
%"GND"
"1","(-4200,2475)","0","mstr_symbols","I96";
;
CDS_LIB"mstr_symbols"
SIZE"1B"
VOLTAGE"0.0V"
BODY_TYPE"PLUMBING"
HDL_POWER"GND";
"A\NAC"18;
%"TC7PZ14FU-GP"
"1","(-3675,4125)","0","w_hdl","I97";
;
CDS_SEC"1"
CDS_LOCATION"U9A4"
VALUE"TC7PZ14FU-GP"
LOCATION"U9A4"
PART_NUMBER"073.7PZ14.0007"
CDS_LMAN_SYM_OUTLINE"-200,150,200,-150"
CDS_LIB"w_hdl"
SEC_TYPE"DISCRET-GA1"
SEC"1"
PACK_TYPE"DISCRET-GA1";
"1Y"
$PN"6"34;
"VCC"
$PN"5"8;
"2Y"
$PN"4"35;
"2A"
$PN"3"34;
"GND"
$PN"2"19;
"1A"
$PN"1"27;
%"GND"
"1","(-4150,3875)","0","mstr_symbols","I98";
;
VOLTAGE"0.0V"
SIZE"1B"
CDS_LIB"mstr_symbols"
BODY_TYPE"PLUMBING"
HDL_POWER"GND";
"A\NAC"19;
%"RES"
"2","(-5875,3075)","0","mstr_discrete","I99";
;
CDS_SEC"1"
CDS_LOCATION"R1L19"
LOCATION"R1L19"
VALUE"4.75K"
TOLERANCE"1%"
WATTAGE"1/16W"
MATERIAL"CHIP"
PART_NUMBER"G21796-072"
PACK_TYPE"0402"
CDS_LIB"mstr_discrete"
ROOM"M-SATA"
BOM_COST"M-SATA"
SEC"1"
SEC_TYPE"0402";
"A"
$PN"1"3;
"B"
$PN"2"22;
END.
